(kicad_pcb
	(version 20260206)
	(generator "pcbnew")
	(generator_version "10.0")
	(general
		(thickness 1.6)
		(legacy_teardrops no)
	)
	(paper "A4")
	(title_block
		(title "Wiwynn_Tioga_Pass_MB.brd")
		(comment 1 "Tioga Pass / footprint 3114 of 4770 (J9U1), pads 1-123 of 291")
	)
	(layers
		(0 "F.Cu" signal "TOP")
		(4 "In1.Cu" signal "L2GND")
		(6 "In2.Cu" signal "L3")
		(8 "In3.Cu" signal "L4GND")
		(10 "In4.Cu" signal "L5")
		(12 "In5.Cu" signal "L6GND")
		(14 "In6.Cu" signal "L7VCC")
		(16 "In7.Cu" signal "L8VCC")
		(18 "In8.Cu" signal "L9GND")
		(20 "In9.Cu" signal "L10")
		(22 "In10.Cu" signal "L11GND")
		(24 "In11.Cu" signal "L12")
		(26 "In12.Cu" signal "L13GND")
		(2 "B.Cu" signal "BOTTOM")
		(9 "F.Adhes" user "F.Adhesive")
		(11 "B.Adhes" user "B.Adhesive")
		(13 "F.Paste" user "Package Geometry/Pastemask Top")
		(15 "B.Paste" user "Package Geometry/Pastemask Bottom")
		(5 "F.SilkS" user "Ref Des/Silkscreen Top")
		(7 "B.SilkS" user "Ref Des/Silkscreen Bottom")
		(1 "F.Mask" user "Board Geometry/Soldermask Top")
		(3 "B.Mask" user "Board Geometry/Soldermask Bottom")
		(17 "Dwgs.User" user "User.Drawings")
		(19 "Cmts.User" user "User.Comments")
		(21 "Eco1.User" user "User.Eco1")
		(23 "Eco2.User" user "User.Eco2")
		(25 "Edge.Cuts" user "Board Geometry/Outline")
		(27 "Margin" user)
		(31 "F.CrtYd" user "Package Geometry/Place Bound Top")
		(29 "B.CrtYd" user "Package Geometry/Place Bound Bottom")
		(35 "F.Fab" user "Ref Des/Assembly Top")
		(33 "B.Fab" user "Ref Des/Assembly Bottom")
	)
	(footprint ""
		(layer "B.Cu")
		(at 29.699458 -15.222982 90)
		(property "Reference" "J9U1"
			(at 2.276348 37.991542 0)
			(unlocked yes)
			(layer "B.SilkS")
			(effects
				(font
					(size 0.7874 0.5842)
					(thickness 0.1524)
				)
				(justify left mirror)
			)
		)
		(property "Value" ""
			(at 0 0 90)
			(layer "B.Fab")
			(effects
				(font
					(size 1.27 1.27)
				)
				(justify mirror)
			)
		)
		(duplicate_pad_numbers_are_jumpers no)
		(pad "" thru_hole circle
			(at -2.29997 -5.649976 270)
			(size 2.8194 2.8194)
			(drill 2.4384)
			(layers "*.Cu" "*.Mask")
			(remove_unused_layers no)
			(clearance 0.127)
			(thermal_gap 0.127)
		)
		(pad "" thru_hole oval
			(at -2.29997 68.90004 270)
			(size 2.8194 1.5748)
			(drill oval 2.4384 1.1938)
			(layers "*.Cu" "*.Mask")
			(remove_unused_layers no)
			(clearance 0.127)
			(thermal_gap 0.127)
		)
		(pad "" thru_hole circle
			(at -2.29997 132.299964 270)
			(size 2.8194 2.8194)
			(drill 2.4384)
			(layers "*.Cu" "*.Mask")
			(remove_unused_layers no)
			(clearance 0.127)
			(thermal_gap 0.127)
		)
		(pad "1" smd rect
			(at 0 0 270)
			(size 1.8034 0.508)
			(layers "B.Cu" "B.Mask" "B.Paste")
			(net "P12V_NVDIMM_GHJ")
		)
		(pad "2" smd rect
			(at 0 0.849884 270)
			(size 1.8034 0.508)
			(layers "B.Cu" "B.Mask" "B.Paste")
			(net "GND")
		)
		(pad "3" smd rect
			(at 0 1.700022 270)
			(size 1.8034 0.508)
			(layers "B.Cu" "B.Mask" "B.Paste")
			(net "M_H_DQ<4>")
		)
		(pad "4" smd rect
			(at 0 2.549906 270)
			(size 1.8034 0.508)
			(layers "B.Cu" "B.Mask" "B.Paste")
			(net "GND")
		)
		(pad "5" smd rect
			(at 0 3.400044 270)
			(size 1.8034 0.508)
			(layers "B.Cu" "B.Mask" "B.Paste")
			(net "M_H_DQ<0>")
		)
		(pad "6" smd rect
			(at 0 4.249928 270)
			(size 1.8034 0.508)
			(layers "B.Cu" "B.Mask" "B.Paste")
			(net "GND")
		)
		(pad "7" smd rect
			(at 0 5.100066 270)
			(size 1.8034 0.508)
			(layers "B.Cu" "B.Mask" "B.Paste")
			(net "M_H_DQS_DP<9>")
		)
		(pad "8" smd rect
			(at 0 5.94995 270)
			(size 1.8034 0.508)
			(layers "B.Cu" "B.Mask" "B.Paste")
			(net "M_H_DQS_DN<9>")
		)
		(pad "9" smd rect
			(at 0 6.800088 270)
			(size 1.8034 0.508)
			(layers "B.Cu" "B.Mask" "B.Paste")
			(net "GND")
		)
		(pad "10" smd rect
			(at 0 7.649972 270)
			(size 1.8034 0.508)
			(layers "B.Cu" "B.Mask" "B.Paste")
			(net "M_H_DQ<6>")
		)
		(pad "11" smd rect
			(at 0 8.50011 270)
			(size 1.8034 0.508)
			(layers "B.Cu" "B.Mask" "B.Paste")
			(net "GND")
		)
		(pad "12" smd rect
			(at 0 9.349994 270)
			(size 1.8034 0.508)
			(layers "B.Cu" "B.Mask" "B.Paste")
			(net "M_H_DQ<2>")
		)
		(pad "13" smd rect
			(at 0 10.199878 270)
			(size 1.8034 0.508)
			(layers "B.Cu" "B.Mask" "B.Paste")
			(net "GND")
		)
		(pad "14" smd rect
			(at 0 11.050016 270)
			(size 1.8034 0.508)
			(layers "B.Cu" "B.Mask" "B.Paste")
			(net "M_H_DQ<12>")
		)
		(pad "15" smd rect
			(at 0 11.8999 270)
			(size 1.8034 0.508)
			(layers "B.Cu" "B.Mask" "B.Paste")
			(net "GND")
		)
		(pad "16" smd rect
			(at 0 12.750038 270)
			(size 1.8034 0.508)
			(layers "B.Cu" "B.Mask" "B.Paste")
			(net "M_H_DQ<8>")
		)
		(pad "17" smd rect
			(at 0 13.599922 270)
			(size 1.8034 0.508)
			(layers "B.Cu" "B.Mask" "B.Paste")
			(net "GND")
		)
		(pad "18" smd rect
			(at 0 14.45006 270)
			(size 1.8034 0.508)
			(layers "B.Cu" "B.Mask" "B.Paste")
			(net "M_H_DQS_DP<10>")
		)
		(pad "19" smd rect
			(at 0 15.299944 270)
			(size 1.8034 0.508)
			(layers "B.Cu" "B.Mask" "B.Paste")
			(net "M_H_DQS_DN<10>")
		)
		(pad "20" smd rect
			(at 0 16.150082 270)
			(size 1.8034 0.508)
			(layers "B.Cu" "B.Mask" "B.Paste")
			(net "GND")
		)
		(pad "21" smd rect
			(at 0 16.999966 270)
			(size 1.8034 0.508)
			(layers "B.Cu" "B.Mask" "B.Paste")
			(net "M_H_DQ<14>")
		)
		(pad "22" smd rect
			(at 0 17.850104 270)
			(size 1.8034 0.508)
			(layers "B.Cu" "B.Mask" "B.Paste")
			(net "GND")
		)
		(pad "23" smd rect
			(at 0 18.699988 270)
			(size 1.8034 0.508)
			(layers "B.Cu" "B.Mask" "B.Paste")
			(net "M_H_DQ<10>")
		)
		(pad "24" smd rect
			(at 0 19.550126 270)
			(size 1.8034 0.508)
			(layers "B.Cu" "B.Mask" "B.Paste")
			(net "GND")
		)
		(pad "25" smd rect
			(at 0 20.40001 270)
			(size 1.8034 0.508)
			(layers "B.Cu" "B.Mask" "B.Paste")
			(net "M_H_DQ<20>")
		)
		(pad "26" smd rect
			(at 0 21.249894 270)
			(size 1.8034 0.508)
			(layers "B.Cu" "B.Mask" "B.Paste")
			(net "GND")
		)
		(pad "27" smd rect
			(at 0 22.100032 270)
			(size 1.8034 0.508)
			(layers "B.Cu" "B.Mask" "B.Paste")
			(net "M_H_DQ<16>")
		)
		(pad "28" smd rect
			(at 0 22.949916 270)
			(size 1.8034 0.508)
			(layers "B.Cu" "B.Mask" "B.Paste")
			(net "GND")
		)
		(pad "29" smd rect
			(at 0 23.800054 270)
			(size 1.8034 0.508)
			(layers "B.Cu" "B.Mask" "B.Paste")
			(net "M_H_DQS_DP<11>")
		)
		(pad "30" smd rect
			(at 0 24.649938 270)
			(size 1.8034 0.508)
			(layers "B.Cu" "B.Mask" "B.Paste")
			(net "M_H_DQS_DN<11>")
		)
		(pad "31" smd rect
			(at 0 25.500076 270)
			(size 1.8034 0.508)
			(layers "B.Cu" "B.Mask" "B.Paste")
			(net "GND")
		)
		(pad "32" smd rect
			(at 0 26.34996 270)
			(size 1.8034 0.508)
			(layers "B.Cu" "B.Mask" "B.Paste")
			(net "M_H_DQ<22>")
		)
		(pad "33" smd rect
			(at 0 27.200098 270)
			(size 1.8034 0.508)
			(layers "B.Cu" "B.Mask" "B.Paste")
			(net "GND")
		)
		(pad "34" smd rect
			(at 0 28.049982 270)
			(size 1.8034 0.508)
			(layers "B.Cu" "B.Mask" "B.Paste")
			(net "M_H_DQ<18>")
		)
		(pad "35" smd rect
			(at 0 28.90012 270)
			(size 1.8034 0.508)
			(layers "B.Cu" "B.Mask" "B.Paste")
			(net "GND")
		)
		(pad "36" smd rect
			(at 0 29.750004 270)
			(size 1.8034 0.508)
			(layers "B.Cu" "B.Mask" "B.Paste")
			(net "M_H_DQ<28>")
		)
		(pad "37" smd rect
			(at 0 30.599888 270)
			(size 1.8034 0.508)
			(layers "B.Cu" "B.Mask" "B.Paste")
			(net "GND")
		)
		(pad "38" smd rect
			(at 0 31.450026 270)
			(size 1.8034 0.508)
			(layers "B.Cu" "B.Mask" "B.Paste")
			(net "M_H_DQ<24>")
		)
		(pad "39" smd rect
			(at 0 32.29991 270)
			(size 1.8034 0.508)
			(layers "B.Cu" "B.Mask" "B.Paste")
			(net "GND")
		)
		(pad "40" smd rect
			(at 0 33.150048 270)
			(size 1.8034 0.508)
			(layers "B.Cu" "B.Mask" "B.Paste")
			(net "M_H_DQS_DP<12>")
		)
		(pad "41" smd rect
			(at 0 33.999932 270)
			(size 1.8034 0.508)
			(layers "B.Cu" "B.Mask" "B.Paste")
			(net "M_H_DQS_DN<12>")
		)
		(pad "42" smd rect
			(at 0 34.85007 270)
			(size 1.8034 0.508)
			(layers "B.Cu" "B.Mask" "B.Paste")
			(net "GND")
		)
		(pad "43" smd rect
			(at 0 35.699954 270)
			(size 1.8034 0.508)
			(layers "B.Cu" "B.Mask" "B.Paste")
			(net "M_H_DQ<30>")
		)
		(pad "44" smd rect
			(at 0 36.550092 270)
			(size 1.8034 0.508)
			(layers "B.Cu" "B.Mask" "B.Paste")
			(net "GND")
		)
		(pad "45" smd rect
			(at 0 37.399976 270)
			(size 1.8034 0.508)
			(layers "B.Cu" "B.Mask" "B.Paste")
			(net "M_H_DQ<26>")
		)
		(pad "46" smd rect
			(at 0 38.250114 270)
			(size 1.8034 0.508)
			(layers "B.Cu" "B.Mask" "B.Paste")
			(net "GND")
		)
		(pad "47" smd rect
			(at 0 39.099998 270)
			(size 1.8034 0.508)
			(layers "B.Cu" "B.Mask" "B.Paste")
			(net "M_H_ECC<4>")
		)
		(pad "48" smd rect
			(at 0 39.949882 270)
			(size 1.8034 0.508)
			(layers "B.Cu" "B.Mask" "B.Paste")
			(net "GND")
		)
		(pad "49" smd rect
			(at 0 40.80002 270)
			(size 1.8034 0.508)
			(layers "B.Cu" "B.Mask" "B.Paste")
			(net "M_H_ECC<0>")
		)
		(pad "50" smd rect
			(at 0 41.649904 270)
			(size 1.8034 0.508)
			(layers "B.Cu" "B.Mask" "B.Paste")
			(net "GND")
		)
		(pad "51" smd rect
			(at 0 42.500042 270)
			(size 1.8034 0.508)
			(layers "B.Cu" "B.Mask" "B.Paste")
			(net "M_H_DQS_DP<17>")
		)
		(pad "52" smd rect
			(at 0 43.349926 270)
			(size 1.8034 0.508)
			(layers "B.Cu" "B.Mask" "B.Paste")
			(net "M_H_DQS_DN<17>")
		)
		(pad "53" smd rect
			(at 0 44.200064 270)
			(size 1.8034 0.508)
			(layers "B.Cu" "B.Mask" "B.Paste")
			(net "GND")
		)
		(pad "54" smd rect
			(at 0 45.049948 270)
			(size 1.8034 0.508)
			(layers "B.Cu" "B.Mask" "B.Paste")
			(net "M_H_ECC<6>")
		)
		(pad "55" smd rect
			(at 0 45.900086 270)
			(size 1.8034 0.508)
			(layers "B.Cu" "B.Mask" "B.Paste")
			(net "GND")
		)
		(pad "56" smd rect
			(at 0 46.74997 270)
			(size 1.8034 0.508)
			(layers "B.Cu" "B.Mask" "B.Paste")
			(net "M_H_ECC<2>")
		)
		(pad "57" smd rect
			(at 0 47.600108 270)
			(size 1.8034 0.508)
			(layers "B.Cu" "B.Mask" "B.Paste")
			(net "GND")
		)
		(pad "58" smd rect
			(at 0 48.449992 270)
			(size 1.8034 0.508)
			(layers "B.Cu" "B.Mask" "B.Paste")
			(net "M_GHJ_RST_N")
		)
		(pad "59" smd rect
			(at 0 49.299876 270)
			(size 1.8034 0.508)
			(layers "B.Cu" "B.Mask" "B.Paste")
			(net "PVDDQ_GHJ")
		)
		(pad "60" smd rect
			(at 0 50.150014 270)
			(size 1.8034 0.508)
			(layers "B.Cu" "B.Mask" "B.Paste")
			(net "M_H_CKE<2>")
		)
		(pad "61" smd rect
			(at 0 50.999898 270)
			(size 1.8034 0.508)
			(layers "B.Cu" "B.Mask" "B.Paste")
			(net "PVDDQ_GHJ")
		)
		(pad "62" smd rect
			(at 0 51.850036 270)
			(size 1.8034 0.508)
			(layers "B.Cu" "B.Mask" "B.Paste")
			(net "M_H_ACT_N")
		)
		(pad "63" smd rect
			(at 0 52.69992 270)
			(size 1.8034 0.508)
			(layers "B.Cu" "B.Mask" "B.Paste")
			(net "M_H_BG<0>")
		)
		(pad "64" smd rect
			(at 0 53.550058 270)
			(size 1.8034 0.508)
			(layers "B.Cu" "B.Mask" "B.Paste")
			(net "PVDDQ_GHJ")
		)
		(pad "65" smd rect
			(at 0 54.399942 270)
			(size 1.8034 0.508)
			(layers "B.Cu" "B.Mask" "B.Paste")
			(net "M_H_MA<12>")
		)
		(pad "66" smd rect
			(at 0 55.25008 270)
			(size 1.8034 0.508)
			(layers "B.Cu" "B.Mask" "B.Paste")
			(net "M_H_MA<9>")
		)
		(pad "67" smd rect
			(at 0 56.099964 270)
			(size 1.8034 0.508)
			(layers "B.Cu" "B.Mask" "B.Paste")
			(net "PVDDQ_GHJ")
		)
		(pad "68" smd rect
			(at 0 56.950102 270)
			(size 1.8034 0.508)
			(layers "B.Cu" "B.Mask" "B.Paste")
			(net "M_H_MA<8>")
		)
		(pad "69" smd rect
			(at 0 57.799986 270)
			(size 1.8034 0.508)
			(layers "B.Cu" "B.Mask" "B.Paste")
			(net "M_H_MA<6>")
		)
		(pad "70" smd rect
			(at 0 58.650124 270)
			(size 1.8034 0.508)
			(layers "B.Cu" "B.Mask" "B.Paste")
			(net "PVDDQ_GHJ")
		)
		(pad "71" smd rect
			(at 0 59.500008 270)
			(size 1.8034 0.508)
			(layers "B.Cu" "B.Mask" "B.Paste")
			(net "M_H_MA<3>")
		)
		(pad "72" smd rect
			(at 0 60.349892 270)
			(size 1.8034 0.508)
			(layers "B.Cu" "B.Mask" "B.Paste")
			(net "M_H_MA<1>")
		)
		(pad "73" smd rect
			(at 0 61.20003 270)
			(size 1.8034 0.508)
			(layers "B.Cu" "B.Mask" "B.Paste")
			(net "PVDDQ_GHJ")
		)
		(pad "74" smd rect
			(at 0 62.049914 270)
			(size 1.8034 0.508)
			(layers "B.Cu" "B.Mask" "B.Paste")
			(net "M_H_CLK_DP<2>")
		)
		(pad "75" smd rect
			(at 0 62.900052 270)
			(size 1.8034 0.508)
			(layers "B.Cu" "B.Mask" "B.Paste")
			(net "M_H_CLK_DN<2>")
		)
		(pad "76" smd rect
			(at 0 63.749936 270)
			(size 1.8034 0.508)
			(layers "B.Cu" "B.Mask" "B.Paste")
			(net "PVDDQ_GHJ")
		)
		(pad "77" smd rect
			(at 0 64.600074 270)
			(size 1.8034 0.508)
			(layers "B.Cu" "B.Mask" "B.Paste")
			(net "PVTT_GHJ")
		)
		(pad "78" smd rect
			(at 0 70.550024 270)
			(size 1.8034 0.508)
			(layers "B.Cu" "B.Mask" "B.Paste")
			(net "FM_DIMM_EVENT_COD_N")
		)
		(pad "79" smd rect
			(at 0 71.399908 270)
			(size 1.8034 0.508)
			(layers "B.Cu" "B.Mask" "B.Paste")
			(net "M_H_MA<0>")
		)
		(pad "80" smd rect
			(at 0 72.250046 270)
			(size 1.8034 0.508)
			(layers "B.Cu" "B.Mask" "B.Paste")
			(net "PVDDQ_GHJ")
		)
		(pad "81" smd rect
			(at 0 73.09993 270)
			(size 1.8034 0.508)
			(layers "B.Cu" "B.Mask" "B.Paste")
			(net "M_H_BA<0>")
		)
		(pad "82" smd rect
			(at 0 73.950068 270)
			(size 1.8034 0.508)
			(layers "B.Cu" "B.Mask" "B.Paste")
			(net "M_H_MA<16>")
		)
		(pad "83" smd rect
			(at 0 74.799952 270)
			(size 1.8034 0.508)
			(layers "B.Cu" "B.Mask" "B.Paste")
			(net "PVDDQ_GHJ")
		)
		(pad "84" smd rect
			(at 0 75.65009 270)
			(size 1.8034 0.508)
			(layers "B.Cu" "B.Mask" "B.Paste")
			(net "M_H_CS_N<4>")
		)
		(pad "85" smd rect
			(at 0 76.499974 270)
			(size 1.8034 0.508)
			(layers "B.Cu" "B.Mask" "B.Paste")
			(net "PVDDQ_GHJ")
		)
		(pad "86" smd rect
			(at 0 77.350112 270)
			(size 1.8034 0.508)
			(layers "B.Cu" "B.Mask" "B.Paste")
			(net "M_H_MA<15>")
		)
		(pad "87" smd rect
			(at 0 78.199996 270)
			(size 1.8034 0.508)
			(layers "B.Cu" "B.Mask" "B.Paste")
			(net "M_H_ODT<2>")
		)
		(pad "88" smd rect
			(at 0 79.04988 270)
			(size 1.8034 0.508)
			(layers "B.Cu" "B.Mask" "B.Paste")
			(net "PVDDQ_GHJ")
		)
		(pad "89" smd rect
			(at 0 79.900018 270)
			(size 1.8034 0.508)
			(layers "B.Cu" "B.Mask" "B.Paste")
			(net "M_H_CS_N<5>")
		)
		(pad "90" smd rect
			(at 0 80.749902 270)
			(size 1.8034 0.508)
			(layers "B.Cu" "B.Mask" "B.Paste")
			(net "PVDDQ_GHJ")
		)
		(pad "91" smd rect
			(at 0 81.60004 270)
			(size 1.8034 0.508)
			(layers "B.Cu" "B.Mask" "B.Paste")
			(net "M_H_ODT<3>")
		)
		(pad "92" smd rect
			(at 0 82.449924 270)
			(size 1.8034 0.508)
			(layers "B.Cu" "B.Mask" "B.Paste")
			(net "PVDDQ_GHJ")
		)
		(pad "93" smd rect
			(at 0 83.300062 270)
			(size 1.8034 0.508)
			(layers "B.Cu" "B.Mask" "B.Paste")
			(net "M_H_CS_N<6>")
		)
		(pad "94" smd rect
			(at 0 84.149946 270)
			(size 1.8034 0.508)
			(layers "B.Cu" "B.Mask" "B.Paste")
			(net "GND")
		)
		(pad "95" smd rect
			(at 0 85.000084 270)
			(size 1.8034 0.508)
			(layers "B.Cu" "B.Mask" "B.Paste")
			(net "M_H_DQ<36>")
		)
		(pad "96" smd rect
			(at 0 85.849968 270)
			(size 1.8034 0.508)
			(layers "B.Cu" "B.Mask" "B.Paste")
			(net "GND")
		)
		(pad "97" smd rect
			(at 0 86.700106 270)
			(size 1.8034 0.508)
			(layers "B.Cu" "B.Mask" "B.Paste")
			(net "M_H_DQ<32>")
		)
		(pad "98" smd rect
			(at 0 87.54999 270)
			(size 1.8034 0.508)
			(layers "B.Cu" "B.Mask" "B.Paste")
			(net "GND")
		)
		(pad "99" smd rect
			(at 0 88.399874 270)
			(size 1.8034 0.508)
			(layers "B.Cu" "B.Mask" "B.Paste")
			(net "M_H_DQS_DP<13>")
		)
		(pad "100" smd rect
			(at 0 89.250012 270)
			(size 1.8034 0.508)
			(layers "B.Cu" "B.Mask" "B.Paste")
			(net "M_H_DQS_DN<13>")
		)
		(pad "101" smd rect
			(at 0 90.099896 270)
			(size 1.8034 0.508)
			(layers "B.Cu" "B.Mask" "B.Paste")
			(net "GND")
		)
		(pad "102" smd rect
			(at 0 90.950034 270)
			(size 1.8034 0.508)
			(layers "B.Cu" "B.Mask" "B.Paste")
			(net "M_H_DQ<38>")
		)
		(pad "103" smd rect
			(at 0 91.799918 270)
			(size 1.8034 0.508)
			(layers "B.Cu" "B.Mask" "B.Paste")
			(net "GND")
		)
		(pad "104" smd rect
			(at 0 92.650056 270)
			(size 1.8034 0.508)
			(layers "B.Cu" "B.Mask" "B.Paste")
			(net "M_H_DQ<34>")
		)
		(pad "105" smd rect
			(at 0 93.49994 270)
			(size 1.8034 0.508)
			(layers "B.Cu" "B.Mask" "B.Paste")
			(net "GND")
		)
		(pad "106" smd rect
			(at 0 94.350078 270)
			(size 1.8034 0.508)
			(layers "B.Cu" "B.Mask" "B.Paste")
			(net "M_H_DQ<44>")
		)
		(pad "107" smd rect
			(at 0 95.199962 270)
			(size 1.8034 0.508)
			(layers "B.Cu" "B.Mask" "B.Paste")
			(net "GND")
		)
		(pad "108" smd rect
			(at 0 96.0501 270)
			(size 1.8034 0.508)
			(layers "B.Cu" "B.Mask" "B.Paste")
			(net "M_H_DQ<40>")
		)
		(pad "109" smd rect
			(at 0 96.899984 270)
			(size 1.8034 0.508)
			(layers "B.Cu" "B.Mask" "B.Paste")
			(net "GND")
		)
		(pad "110" smd rect
			(at 0 97.750122 270)
			(size 1.8034 0.508)
			(layers "B.Cu" "B.Mask" "B.Paste")
			(net "M_H_DQS_DP<14>")
		)
		(pad "111" smd rect
			(at 0 98.600006 270)
			(size 1.8034 0.508)
			(layers "B.Cu" "B.Mask" "B.Paste")
			(net "M_H_DQS_DN<14>")
		)
		(pad "112" smd rect
			(at 0 99.44989 270)
			(size 1.8034 0.508)
			(layers "B.Cu" "B.Mask" "B.Paste")
			(net "GND")
		)
		(pad "113" smd rect
			(at 0 100.300028 270)
			(size 1.8034 0.508)
			(layers "B.Cu" "B.Mask" "B.Paste")
			(net "M_H_DQ<46>")
		)
		(pad "114" smd rect
			(at 0 101.149912 270)
			(size 1.8034 0.508)
			(layers "B.Cu" "B.Mask" "B.Paste")
			(net "GND")
		)
		(pad "115" smd rect
			(at 0 102.00005 270)
			(size 1.8034 0.508)
			(layers "B.Cu" "B.Mask" "B.Paste")
			(net "M_H_DQ<42>")
		)
		(pad "116" smd rect
			(at 0 102.849934 270)
			(size 1.8034 0.508)
			(layers "B.Cu" "B.Mask" "B.Paste")
			(net "GND")
		)
		(pad "117" smd rect
			(at 0 103.700072 270)
			(size 1.8034 0.508)
			(layers "B.Cu" "B.Mask" "B.Paste")
			(net "M_H_DQ<52>")
		)
		(pad "118" smd rect
			(at 0 104.549956 270)
			(size 1.8034 0.508)
			(layers "B.Cu" "B.Mask" "B.Paste")
			(net "GND")
		)
		(pad "119" smd rect
			(at 0 105.400094 270)
			(size 1.8034 0.508)
			(layers "B.Cu" "B.Mask" "B.Paste")
			(net "M_H_DQ<48>")
		)
		(pad "120" smd rect
			(at 0 106.249978 270)
			(size 1.8034 0.508)
			(layers "B.Cu" "B.Mask" "B.Paste")
			(net "GND")
		)
	)
)
